# T6G (Grand Teton) — schematic netlist excerpt (pin names and nets, part order shuffled) for the footprints in the layout excerpt that follows; sources: Cadence DE-HDL packaged netlist, KiCad conversion of 04192023_DAF0TMB3IC0_F0TG_MB_C_brd_V02_OCP.brd

R2941  Q_RES  100K 1% CHIP  pkg 0402LF  page 241 : A = FM_GPU_HSC_EN ; B = GND

U218  74LVC1G07GV  IC  pkg SC-74A_2-9X1-5  page 139
  NC1  = NC_U218_NC1
  A  = FM_SYS_THROTTLE_N
  GND  = GND
  Y  = OCP_V3_2_PWRBRK_BUFF_N
  VCC  = P3V3_AUX

(kicad_pcb
	(version 20260206)
	(generator "pcbnew")
	(generator_version "10.0")
	(general
		(thickness 1.6)
		(legacy_teardrops no)
	)
	(paper "A4")
	(title_block
		(title "04192023_DAF0TMB3IC0_F0TG_MB_C_brd_V02_OCP.brd")
		(comment 1 "Grand Teton / footprints 1480-1481 of 8354")
	)
	(layers
		(0 "F.Cu" signal "TOP")
		(4 "In1.Cu" signal "GND")
		(6 "In2.Cu" signal "IN1")
		(8 "In3.Cu" signal "GND1")
		(10 "In4.Cu" signal "IN2")
		(12 "In5.Cu" signal "GND2")
		(14 "In6.Cu" signal "IN3")
		(16 "In7.Cu" signal "GND3")
		(18 "In8.Cu" signal "VCC")
		(20 "In9.Cu" signal "VCC1")
		(22 "In10.Cu" signal "GND4")
		(24 "In11.Cu" signal "IN4")
		(26 "In12.Cu" signal "GND5")
		(28 "In13.Cu" signal "IN5")
		(30 "In14.Cu" signal "GND6")
		(32 "In15.Cu" signal "IN6")
		(34 "In16.Cu" signal "GND7")
		(2 "B.Cu" signal "BOTTOM")
		(9 "F.Adhes" user "F.Adhesive")
		(11 "B.Adhes" user "B.Adhesive")
		(13 "F.Paste" user "Package Geometry/Pastemask Top")
		(15 "B.Paste" user "Package Geometry/Pastemask Bottom")
		(5 "F.SilkS" user "Ref Des/Silkscreen Top")
		(7 "B.SilkS" user "Ref Des/Silkscreen Bottom")
		(1 "F.Mask" user "Board Geometry/Soldermask Top")
		(3 "B.Mask" user "Board Geometry/Soldermask Bottom")
		(17 "Dwgs.User" user "User.Drawings")
		(19 "Cmts.User" user "User.Comments")
		(21 "Eco1.User" user "User.Eco1")
		(23 "Eco2.User" user "User.Eco2")
		(25 "Edge.Cuts" user "Board Geometry/Outline")
		(27 "Margin" user)
		(31 "F.CrtYd" user "Package Geometry/Place Bound Top")
		(29 "B.CrtYd" user "Package Geometry/Place Bound Bottom")
		(35 "F.Fab" user "Ref Des/Assembly Top")
		(33 "B.Fab" user "Ref Des/Assembly Bottom")
	)
	(footprint ""
		(layer "F.Cu")
		(at 190.94958 -413.964882 -90)
		(property "Reference" "R2941"
			(at 0 0 270)
			(layer "F.SilkS")
			(hide yes)
			(effects
				(font
					(size 1.27 1.27)
				)
			)
		)
		(property "Value" ""
			(at 0 0 270)
			(layer "F.Fab")
			(effects
				(font
					(size 1.27 1.27)
				)
			)
		)
		(duplicate_pad_numbers_are_jumpers no)
		(fp_line
			(start -0.7874 0.4064)
			(end -0.7874 -0.4064)
			(stroke
				(width 0.1524)
				(type default)
			)
			(layer "F.SilkS")
		)
		(fp_line
			(start 0.7874 0.4064)
			(end -0.7874 0.4064)
			(stroke
				(width 0.1524)
				(type default)
			)
			(layer "F.SilkS")
		)
		(fp_line
			(start -0.7874 -0.4064)
			(end 0.7874 -0.4064)
			(stroke
				(width 0.1524)
				(type default)
			)
			(layer "F.SilkS")
		)
		(fp_line
			(start 0.7874 -0.4064)
			(end 0.7874 0.4064)
			(stroke
				(width 0.1524)
				(type default)
			)
			(layer "F.SilkS")
		)
		(fp_line
			(start -0.67945 0.3048)
			(end -0.67945 -0.305054)
			(stroke
				(width 0.1)
				(type default)
			)
			(layer "F.Fab")
		)
		(fp_line
			(start -0.12065 0.3048)
			(end -0.67945 0.3048)
			(stroke
				(width 0.1)
				(type default)
			)
			(layer "F.Fab")
		)
		(fp_line
			(start 0.120396 0.3048)
			(end 0.120396 0.2794)
			(stroke
				(width 0.1)
				(type default)
			)
			(layer "F.Fab")
		)
		(fp_line
			(start 0.67945 0.3048)
			(end 0.120396 0.3048)
			(stroke
				(width 0.1)
				(type default)
			)
			(layer "F.Fab")
		)
		(fp_line
			(start -0.12065 0.2794)
			(end -0.12065 0.3048)
			(stroke
				(width 0.1)
				(type default)
			)
			(layer "F.Fab")
		)
		(fp_line
			(start 0.120396 0.2794)
			(end -0.12065 0.2794)
			(stroke
				(width 0.1)
				(type default)
			)
			(layer "F.Fab")
		)
		(fp_line
			(start -0.12065 -0.2794)
			(end 0.12065 -0.2794)
			(stroke
				(width 0.1)
				(type default)
			)
			(layer "F.Fab")
		)
		(fp_line
			(start 0.12065 -0.2794)
			(end 0.12065 -0.3048)
			(stroke
				(width 0.1)
				(type default)
			)
			(layer "F.Fab")
		)
		(fp_line
			(start 0.12065 -0.3048)
			(end 0.67945 -0.3048)
			(stroke
				(width 0.1)
				(type default)
			)
			(layer "F.Fab")
		)
		(fp_line
			(start 0.67945 -0.3048)
			(end 0.67945 0.3048)
			(stroke
				(width 0.1)
				(type default)
			)
			(layer "F.Fab")
		)
		(fp_line
			(start -0.67945 -0.305054)
			(end -0.12065 -0.305054)
			(stroke
				(width 0.1)
				(type default)
			)
			(layer "F.Fab")
		)
		(fp_line
			(start -0.12065 -0.305054)
			(end -0.12065 -0.2794)
			(stroke
				(width 0.1)
				(type default)
			)
			(layer "F.Fab")
		)
		(pad "1" smd circle
			(at -0.40005 0 270)
			(size 0 0)
			(layers "F.Cu" "F.Mask" "F.Paste")
			(net "FM_GPU_HSC_EN")
		)
		(pad "2" smd circle
			(at 0.40005 0 270)
			(size 0 0)
			(layers "F.Cu" "F.Mask" "F.Paste")
			(net "GND")
		)
	)
	(footprint ""
		(layer "F.Cu")
		(at 253.340108 -107.855004)
		(property "Reference" "U218"
			(at -1.4351 2.394712 0)
			(unlocked yes)
			(layer "F.SilkS")
			(effects
				(font
					(size 0.7874 0.5842)
					(thickness 0.1524)
				)
				(justify left)
			)
		)
		(property "Value" ""
			(at 0 0 0)
			(layer "F.Fab")
			(effects
				(font
					(size 1.27 1.27)
				)
			)
		)
		(duplicate_pad_numbers_are_jumpers no)
		(fp_line
			(start -1.733296 -1.549908)
			(end -1.733296 1.549908)
			(stroke
				(width 0.1524)
				(type default)
			)
			(layer "F.SilkS")
		)
		(fp_line
			(start -1.733296 1.549908)
			(end 1.733296 1.549908)
			(stroke
				(width 0.1524)
				(type default)
			)
			(layer "F.SilkS")
		)
		(fp_line
			(start -0.660908 -1.549908)
			(end -1.733296 -1.549908)
			(stroke
				(width 0.1524)
				(type default)
			)
			(layer "F.SilkS")
		)
		(fp_line
			(start 0 -0.889)
			(end -0.660908 -1.549908)
			(stroke
				(width 0.1524)
				(type default)
			)
			(layer "F.SilkS")
		)
		(fp_line
			(start 0.660908 -1.549908)
			(end 0 -0.889)
			(stroke
				(width 0.1524)
				(type default)
			)
			(layer "F.SilkS")
		)
		(fp_line
			(start 1.733296 -1.549908)
			(end 0.660908 -1.549908)
			(stroke
				(width 0.1524)
				(type default)
			)
			(layer "F.SilkS")
		)
		(fp_line
			(start 1.733296 1.549908)
			(end 1.733296 -1.549908)
			(stroke
				(width 0.1524)
				(type default)
			)
			(layer "F.SilkS")
		)
		(fp_poly
			(pts
				(xy -1.172464 -1.626108) (xy -1.426464 -2.134108) (xy -0.918464 -2.134108)
			)
			(stroke
				(width 0)
				(type default)
			)
			(fill yes)
			(layer "F.SilkS")
		)
		(fp_line
			(start -0.849884 -1.549908)
			(end -0.849884 1.549908)
			(stroke
				(width 0.1)
				(type default)
			)
			(layer "F.Fab")
		)
		(fp_line
			(start -0.849884 1.549908)
			(end 0.849884 1.549908)
			(stroke
				(width 0.1)
				(type default)
			)
			(layer "F.Fab")
		)
		(fp_line
			(start 0.849884 -1.549908)
			(end -0.849884 -1.549908)
			(stroke
				(width 0.1)
				(type default)
			)
			(layer "F.Fab")
		)
		(fp_line
			(start 0.849884 1.549908)
			(end 0.849884 -1.549908)
			(stroke
				(width 0.1)
				(type default)
			)
			(layer "F.Fab")
		)
		(fp_poly
			(pts
				(xy -2.4384 -1.20396) (xy -2.4384 -0.69596) (xy -1.9304 -0.94996)
			)
			(stroke
				(width 0)
				(type default)
			)
			(fill yes)
			(layer "F.Fab")
		)
		(pad "1" smd rect
			(at -1.199896 -0.94996 270)
			(size 0.5588 0.8128)
			(layers "F.Cu" "F.Mask" "F.Paste")
			(net "NC_U218_NC1")
		)
		(pad "2" smd rect
			(at -1.199896 0 270)
			(size 0.5588 0.8128)
			(layers "F.Cu" "F.Mask" "F.Paste")
			(net "FM_SYS_THROTTLE_N")
		)
		(pad "3" smd rect
			(at -1.199896 0.94996 270)
			(size 0.5588 0.8128)
			(layers "F.Cu" "F.Mask" "F.Paste")
			(net "GND")
		)
		(pad "4" smd rect
			(at 1.199896 0.94996 270)
			(size 0.5588 0.8128)
			(layers "F.Cu" "F.Mask" "F.Paste")
			(net "OCP_V3_2_PWRBRK_BUFF_N")
		)
		(pad "5" smd rect
			(at 1.199896 -0.94996 270)
			(size 0.5588 0.8128)
			(layers "F.Cu" "F.Mask" "F.Paste")
			(net "P3V3_AUX")
		)
	)
)
